(kicad_pcb
	(version 20260206)
	(generator "pcbnew")
	(generator_version "10.0")
	(general
		(thickness 1.6)
		(legacy_teardrops no)
	)
	(paper "A4")
	(title_block
		(title "Bryce Canyon_F.DPB_16315-1-OCP.brd")
		(comment 1 "Bryce Canyon / footprints 519-526 of 2223")
	)
	(layers
		(0 "F.Cu" signal "TOP")
		(4 "In1.Cu" signal "L2GND")
		(6 "In2.Cu" signal "L3")
		(8 "In3.Cu" signal "L4GND")
		(10 "In4.Cu" signal "L5")
		(12 "In5.Cu" signal "L6VCC")
		(14 "In6.Cu" signal "L7VCC")
		(16 "In7.Cu" signal "L8")
		(18 "In8.Cu" signal "L9GND")
		(20 "In9.Cu" signal "L10")
		(22 "In10.Cu" signal "L11GND")
		(2 "B.Cu" signal "BOTTOM")
		(9 "F.Adhes" user "F.Adhesive")
		(11 "B.Adhes" user "B.Adhesive")
		(13 "F.Paste" user "Package Geometry/Pastemask Top")
		(15 "B.Paste" user "Package Geometry/Pastemask Bottom")
		(5 "F.SilkS" user "Ref Des/Silkscreen Top")
		(7 "B.SilkS" user "Ref Des/Silkscreen Bottom")
		(1 "F.Mask" user "Board Geometry/Soldermask Top")
		(3 "B.Mask" user "Board Geometry/Soldermask Bottom")
		(17 "Dwgs.User" user "User.Drawings")
		(19 "Cmts.User" user "User.Comments")
		(21 "Eco1.User" user "User.Eco1")
		(23 "Eco2.User" user "User.Eco2")
		(25 "Edge.Cuts" user "Board Geometry/Outline")
		(27 "Margin" user)
		(31 "F.CrtYd" user "Package Geometry/Place Bound Top")
		(29 "B.CrtYd" user "Package Geometry/Place Bound Bottom")
		(35 "F.Fab" user "Ref Des/Assembly Top")
		(33 "B.Fab" user "Ref Des/Assembly Bottom")
	)
	(footprint ""
		(layer "F.Cu")
		(at 415.909252 -291.127942 -90)
		(property "Reference" "C163"
			(at 0 0 270)
			(layer "F.SilkS")
			(hide yes)
			(effects
				(font
					(size 1.27 1.27)
				)
			)
		)
		(property "Value" "SCD01U50V2KX-1GP"
			(at 1.1811 -2.7051 270)
			(unlocked yes)
			(layer "F.Fab")
			(hide yes)
			(effects
				(font
					(size 1.016 1.016)
					(thickness 0.1524)
				)
			)
		)
		(property "Device Type" "C402H22"
			(at 1.1811 -4.2291 270)
			(unlocked yes)
			(layer "F.Fab")
			(hide yes)
			(effects
				(font
					(size 1.016 1.016)
					(thickness 0.1524)
				)
			)
		)
		(duplicate_pad_numbers_are_jumpers no)
		(fp_rect
			(start -0.4318 0.9525)
			(end 0.4318 -0.9525)
			(stroke
				(width 0)
				(type default)
			)
			(fill no)
			(layer "F.CrtYd")
		)
		(fp_rect
			(start -0.4318 0.9525)
			(end 0.4318 -0.9525)
			(stroke
				(width 0)
				(type default)
			)
			(fill no)
			(layer "F.Fab")
		)
		(pad "1" smd custom
			(at 0 -0.4445 270)
			(size 0.1524 0.1524)
			(layers "F.Cu" "F.Mask" "F.Paste")
			(net "HDD_PRSNT_9")
			(options
				(clearance outline)
				(anchor circle)
			)
			(primitives
				(gr_poly
					(pts
						(arc
							(start 0.3048 -0.2032)
							(mid 0.275042 -0.275042)
							(end 0.2032 -0.3048)
						)
						(arc
							(start -0.2032 -0.3048)
							(mid -0.275042 -0.275042)
							(end -0.3048 -0.2032)
						)
						(arc
							(start -0.3048 0.2032)
							(mid -0.275042 0.275042)
							(end -0.2032 0.3048)
						)
						(arc
							(start 0.2032 0.3048)
							(mid 0.275042 0.275042)
							(end 0.3048 0.2032)
						)
					)
					(width 0)
					(fill yes)
				)
			)
		)
		(pad "2" smd custom
			(at 0 0.4445 270)
			(size 0.1524 0.1524)
			(layers "F.Cu" "F.Mask" "F.Paste")
			(net "GND")
			(options
				(clearance outline)
				(anchor circle)
			)
			(primitives
				(gr_poly
					(pts
						(arc
							(start 0.3048 -0.2032)
							(mid 0.275042 -0.275042)
							(end 0.2032 -0.3048)
						)
						(arc
							(start -0.2032 -0.3048)
							(mid -0.275042 -0.275042)
							(end -0.3048 -0.2032)
						)
						(arc
							(start -0.3048 0.2032)
							(mid -0.275042 0.275042)
							(end -0.2032 0.3048)
						)
						(arc
							(start 0.2032 0.3048)
							(mid 0.275042 0.275042)
							(end 0.3048 0.2032)
						)
					)
					(width 0)
					(fill yes)
				)
			)
		)
	)
	(footprint ""
		(layer "F.Cu")
		(at 396.34795 -42.585894 180)
		(property "Reference" "R874"
			(at 0 0 180)
			(layer "F.SilkS")
			(hide yes)
			(effects
				(font
					(size 1.27 1.27)
				)
			)
		)
		(property "Value" "100KR2F-L1-GP"
			(at 0.064008 -3.993896 180)
			(unlocked yes)
			(layer "F.Fab")
			(hide yes)
			(effects
				(font
					(size 1.016 1.016)
					(thickness 0.1524)
				)
			)
		)
		(property "Device Type" "R402H16"
			(at 0.064008 -5.517896 180)
			(unlocked yes)
			(layer "F.Fab")
			(hide yes)
			(effects
				(font
					(size 1.016 1.016)
					(thickness 0.1524)
				)
			)
		)
		(duplicate_pad_numbers_are_jumpers no)
		(fp_line
			(start 0.508 -0.9398)
			(end -0.508 -0.9398)
			(stroke
				(width 0.1524)
				(type default)
			)
			(layer "F.SilkS")
		)
		(fp_line
			(start -0.508 -0.9398)
			(end -0.508 0.9398)
			(stroke
				(width 0.1524)
				(type default)
			)
			(layer "F.SilkS")
		)
		(fp_rect
			(start -0.508 0.9398)
			(end 0.508 -0.9398)
			(stroke
				(width 0)
				(type default)
			)
			(fill no)
			(layer "F.CrtYd")
		)
		(fp_rect
			(start -0.508 0.9398)
			(end 0.508 -0.9398)
			(stroke
				(width 0)
				(type default)
			)
			(fill no)
			(layer "F.Fab")
		)
		(pad "1" smd custom
			(at 0 -0.4445 180)
			(size 0.1397 0.1397)
			(layers "F.Cu" "F.Mask" "F.Paste")
			(net "P3V3_STBY_A")
			(options
				(clearance outline)
				(anchor circle)
			)
			(primitives
				(gr_poly
					(pts
						(arc
							(start -0.1778 -0.2794)
							(mid -0.249642 -0.249642)
							(end -0.2794 -0.1778)
						)
						(arc
							(start -0.2794 0.1778)
							(mid -0.249642 0.249642)
							(end -0.1778 0.2794)
						)
						(arc
							(start 0.1778 0.2794)
							(mid 0.249642 0.249642)
							(end 0.2794 0.1778)
						)
						(arc
							(start 0.2794 -0.1778)
							(mid 0.249642 -0.249642)
							(end 0.1778 -0.2794)
						)
					)
					(width 0)
					(fill yes)
				)
			)
		)
		(pad "2" smd custom
			(at 0 0.4445 180)
			(size 0.1397 0.1397)
			(layers "F.Cu" "F.Mask" "F.Paste")
			(net "SW_PWR_R_HDD32")
			(options
				(clearance outline)
				(anchor circle)
			)
			(primitives
				(gr_poly
					(pts
						(arc
							(start -0.1778 -0.2794)
							(mid -0.249642 -0.249642)
							(end -0.2794 -0.1778)
						)
						(arc
							(start -0.2794 0.1778)
							(mid -0.249642 0.249642)
							(end -0.1778 0.2794)
						)
						(arc
							(start 0.1778 0.2794)
							(mid 0.249642 0.249642)
							(end 0.2794 0.1778)
						)
						(arc
							(start 0.2794 -0.1778)
							(mid 0.249642 -0.249642)
							(end 0.1778 -0.2794)
						)
					)
					(width 0)
					(fill yes)
				)
			)
		)
	)
	(footprint ""
		(layer "F.Cu")
		(at 253.414276 -248.87936)
		(property "Reference" "R54"
			(at 0 0 0)
			(layer "F.SilkS")
			(hide yes)
			(effects
				(font
					(size 1.27 1.27)
				)
			)
		)
		(property "Value" "4K7R2F-GP"
			(at 0.064008 -3.993896 0)
			(unlocked yes)
			(layer "F.Fab")
			(hide yes)
			(effects
				(font
					(size 1.016 1.016)
					(thickness 0.1524)
				)
			)
		)
		(property "Device Type" "R402H16"
			(at 0.064008 -5.517896 0)
			(unlocked yes)
			(layer "F.Fab")
			(hide yes)
			(effects
				(font
					(size 1.016 1.016)
					(thickness 0.1524)
				)
			)
		)
		(duplicate_pad_numbers_are_jumpers no)
		(fp_line
			(start -0.508 -0.9398)
			(end -0.508 0.9398)
			(stroke
				(width 0.1524)
				(type default)
			)
			(layer "F.SilkS")
		)
		(fp_line
			(start 0.508 -0.9398)
			(end -0.508 -0.9398)
			(stroke
				(width 0.1524)
				(type default)
			)
			(layer "F.SilkS")
		)
		(fp_rect
			(start -0.508 0.9398)
			(end 0.508 -0.9398)
			(stroke
				(width 0)
				(type default)
			)
			(fill no)
			(layer "F.CrtYd")
		)
		(fp_rect
			(start -0.508 0.9398)
			(end 0.508 -0.9398)
			(stroke
				(width 0)
				(type default)
			)
			(fill no)
			(layer "F.Fab")
		)
		(pad "1" smd custom
			(at 0 -0.4445)
			(size 0.1397 0.1397)
			(layers "F.Cu" "F.Mask" "F.Paste")
			(net "IO_EXP6_A1")
			(options
				(clearance outline)
				(anchor circle)
			)
			(primitives
				(gr_poly
					(pts
						(arc
							(start -0.1778 -0.2794)
							(mid -0.249642 -0.249642)
							(end -0.2794 -0.1778)
						)
						(arc
							(start -0.2794 0.1778)
							(mid -0.249642 0.249642)
							(end -0.1778 0.2794)
						)
						(arc
							(start 0.1778 0.2794)
							(mid 0.249642 0.249642)
							(end 0.2794 0.1778)
						)
						(arc
							(start 0.2794 -0.1778)
							(mid 0.249642 -0.249642)
							(end 0.1778 -0.2794)
						)
					)
					(width 0)
					(fill yes)
				)
			)
		)
		(pad "2" smd custom
			(at 0 0.4445)
			(size 0.1397 0.1397)
			(layers "F.Cu" "F.Mask" "F.Paste")
			(net "GND")
			(options
				(clearance outline)
				(anchor circle)
			)
			(primitives
				(gr_poly
					(pts
						(arc
							(start -0.1778 -0.2794)
							(mid -0.249642 -0.249642)
							(end -0.2794 -0.1778)
						)
						(arc
							(start -0.2794 0.1778)
							(mid -0.249642 0.249642)
							(end -0.1778 0.2794)
						)
						(arc
							(start 0.1778 0.2794)
							(mid 0.249642 0.249642)
							(end 0.2794 0.1778)
						)
						(arc
							(start 0.2794 -0.1778)
							(mid 0.249642 -0.249642)
							(end 0.1778 -0.2794)
						)
					)
					(width 0)
					(fill yes)
				)
			)
		)
	)
	(footprint ""
		(layer "F.Cu")
		(at 174.625 -276.649942 180)
		(property "Reference" "D5"
			(at 0 0 180)
			(layer "F.SilkS")
			(hide yes)
			(effects
				(font
					(size 1.27 1.27)
				)
			)
		)
		(property "Value" "RB551V30-GP"
			(at 0 -6.7818 180)
			(unlocked yes)
			(layer "F.Fab")
			(hide yes)
			(effects
				(font
					(size 1.016 1.016)
					(thickness 0.1524)
				)
			)
		)
		(property "Device Type" "SOD323AKH38"
			(at 0 -8.6868 180)
			(unlocked yes)
			(layer "F.Fab")
			(hide yes)
			(effects
				(font
					(size 1.016 1.016)
					(thickness 0.1524)
				)
			)
		)
		(duplicate_pad_numbers_are_jumpers no)
		(fp_line
			(start 0.889 2.159)
			(end -0.889 2.159)
			(stroke
				(width 0.1524)
				(type default)
			)
			(layer "F.SilkS")
		)
		(fp_line
			(start 0.889 -1.9304)
			(end 0.889 2.159)
			(stroke
				(width 0.1524)
				(type default)
			)
			(layer "F.SilkS")
		)
		(fp_line
			(start 0.762 2.0574)
			(end -0.762 2.0574)
			(stroke
				(width 0.508)
				(type default)
			)
			(layer "F.SilkS")
		)
		(fp_line
			(start -0.889 2.159)
			(end -0.889 -1.9304)
			(stroke
				(width 0.1524)
				(type default)
			)
			(layer "F.SilkS")
		)
		(fp_line
			(start -0.889 -1.9304)
			(end 0.889 -1.9304)
			(stroke
				(width 0.1524)
				(type default)
			)
			(layer "F.SilkS")
		)
		(fp_rect
			(start -1.016 2.3114)
			(end 1.016 -2.0066)
			(stroke
				(width 0)
				(type default)
			)
			(fill no)
			(layer "F.CrtYd")
		)
		(fp_poly
			(pts
				(xy -1.016 -2.0066) (xy 1.016 -2.0066) (xy 1.016 2.3114) (xy -1.016 2.3114)
			)
			(stroke
				(width 0)
				(type default)
			)
			(fill no)
			(layer "F.Fab")
		)
		(pad "A" smd rect
			(at 0 -1.143 180)
			(size 0.5588 1.016)
			(layers "F.Cu" "F.Mask" "F.Paste")
			(net "SW_HDD_R5")
		)
		(pad "K" smd rect
			(at 0 1.143 180)
			(size 0.5588 1.016)
			(layers "F.Cu" "F.Mask" "F.Paste")
			(net "SW_HDD_N5")
		)
	)
	(footprint ""
		(layer "F.Cu")
		(at 272.542 -310.90489 180)
		(property "Reference" "VIA65"
			(at 0 0 180)
			(layer "F.SilkS")
			(hide yes)
			(effects
				(font
					(size 1.27 1.27)
				)
			)
		)
		(property "Value" "100OHM-8L-1D6MM-L18L16-GP"
			(at -3.7211 -4.5085 180)
			(unlocked yes)
			(layer "F.Fab")
			(hide yes)
			(effects
				(font
					(size 1.016 1.016)
					(thickness 0.1524)
				)
			)
		)
		(property "Device Type" "VIA-PCIE-4P-394076"
			(at -3.7211 -6.0325 180)
			(unlocked yes)
			(layer "F.Fab")
			(hide yes)
			(effects
				(font
					(size 1.016 1.016)
					(thickness 0.1524)
				)
			)
		)
		(duplicate_pad_numbers_are_jumpers no)
		(fp_rect
			(start -1.9685 0.381)
			(end 1.9685 -0.381)
			(stroke
				(width 0)
				(type default)
			)
			(fill no)
			(layer "F.CrtYd")
		)
		(fp_rect
			(start -1.9685 0.381)
			(end 1.9685 -0.381)
			(stroke
				(width 0)
				(type default)
			)
			(fill no)
			(layer "F.Fab")
		)
		(pad "1" thru_hole circle
			(at -1.5875 0 180)
			(size 0.508 0.508)
			(drill 0.254)
			(layers "*.Cu" "*.Mask")
			(remove_unused_layers no)
			(net "GND")
			(clearance 0.127)
			(thermal_gap 0.127)
		)
		(pad "2" thru_hole circle
			(at -0.5715 0 180)
			(size 0.508 0.508)
			(drill 0.254)
			(layers "*.Cu" "*.Mask")
			(remove_unused_layers no)
			(net "PHY_SCC_A_TO_DRV_A_27_DP")
			(clearance 0.127)
			(thermal_gap 0.127)
		)
		(pad "3" thru_hole circle
			(at 0.5715 0 180)
			(size 0.508 0.508)
			(drill 0.254)
			(layers "*.Cu" "*.Mask")
			(remove_unused_layers no)
			(net "PHY_SCC_A_TO_DRV_A_27_DN")
			(clearance 0.127)
			(thermal_gap 0.127)
		)
		(pad "4" thru_hole circle
			(at 1.5875 0 180)
			(size 0.508 0.508)
			(drill 0.254)
			(layers "*.Cu" "*.Mask")
			(remove_unused_layers no)
			(net "GND")
			(clearance 0.127)
			(thermal_gap 0.127)
		)
	)
	(footprint ""
		(layer "F.Cu")
		(at 273.812 -272.288 180)
		(property "Reference" "R117"
			(at 0 0 180)
			(layer "F.SilkS")
			(hide yes)
			(effects
				(font
					(size 1.27 1.27)
				)
			)
		)
		(property "Value" "4K7R2F-GP"
			(at 0.064008 -3.993896 180)
			(unlocked yes)
			(layer "F.Fab")
			(hide yes)
			(effects
				(font
					(size 1.016 1.016)
					(thickness 0.1524)
				)
			)
		)
		(property "Device Type" "R402H16"
			(at 0.064008 -5.517896 180)
			(unlocked yes)
			(layer "F.Fab")
			(hide yes)
			(effects
				(font
					(size 1.016 1.016)
					(thickness 0.1524)
				)
			)
		)
		(duplicate_pad_numbers_are_jumpers no)
		(fp_line
			(start 0.508 -0.9398)
			(end -0.508 -0.9398)
			(stroke
				(width 0.1524)
				(type default)
			)
			(layer "F.SilkS")
		)
		(fp_line
			(start -0.508 -0.9398)
			(end -0.508 0.9398)
			(stroke
				(width 0.1524)
				(type default)
			)
			(layer "F.SilkS")
		)
		(fp_rect
			(start -0.508 0.9398)
			(end 0.508 -0.9398)
			(stroke
				(width 0)
				(type default)
			)
			(fill no)
			(layer "F.CrtYd")
		)
		(fp_rect
			(start -0.508 0.9398)
			(end 0.508 -0.9398)
			(stroke
				(width 0)
				(type default)
			)
			(fill no)
			(layer "F.Fab")
		)
		(pad "1" smd custom
			(at 0 -0.4445 180)
			(size 0.1397 0.1397)
			(layers "F.Cu" "F.Mask" "F.Paste")
			(net "P3V3_STBY_A")
			(options
				(clearance outline)
				(anchor circle)
			)
			(primitives
				(gr_poly
					(pts
						(arc
							(start -0.1778 -0.2794)
							(mid -0.249642 -0.249642)
							(end -0.2794 -0.1778)
						)
						(arc
							(start -0.2794 0.1778)
							(mid -0.249642 0.249642)
							(end -0.1778 0.2794)
						)
						(arc
							(start 0.1778 0.2794)
							(mid 0.249642 0.249642)
							(end 0.2794 0.1778)
						)
						(arc
							(start 0.2794 -0.1778)
							(mid 0.249642 -0.249642)
							(end 0.1778 -0.2794)
						)
					)
					(width 0)
					(fill yes)
				)
			)
		)
		(pad "2" smd custom
			(at 0 0.4445 180)
			(size 0.1397 0.1397)
			(layers "F.Cu" "F.Mask" "F.Paste")
			(net "IO_EXP1_HDD_FAULT_A1")
			(options
				(clearance outline)
				(anchor circle)
			)
			(primitives
				(gr_poly
					(pts
						(arc
							(start -0.1778 -0.2794)
							(mid -0.249642 -0.249642)
							(end -0.2794 -0.1778)
						)
						(arc
							(start -0.2794 0.1778)
							(mid -0.249642 0.249642)
							(end -0.1778 0.2794)
						)
						(arc
							(start 0.1778 0.2794)
							(mid 0.249642 0.249642)
							(end 0.2794 0.1778)
						)
						(arc
							(start 0.2794 -0.1778)
							(mid 0.249642 -0.249642)
							(end 0.1778 -0.2794)
						)
					)
					(width 0)
					(fill yes)
				)
			)
		)
	)
	(footprint ""
		(layer "F.Cu")
		(at 22.970998 -44.871894 -90)
		(property "Reference" "R693"
			(at 0 0 270)
			(layer "F.SilkS")
			(hide yes)
			(effects
				(font
					(size 1.27 1.27)
				)
			)
		)
		(property "Value" "0R2J-2-GP"
			(at 0.064008 -3.993896 270)
			(unlocked yes)
			(layer "F.Fab")
			(hide yes)
			(effects
				(font
					(size 1.016 1.016)
					(thickness 0.1524)
				)
			)
		)
		(property "Device Type" "R402H16"
			(at 0.064008 -5.517896 270)
			(unlocked yes)
			(layer "F.Fab")
			(hide yes)
			(effects
				(font
					(size 1.016 1.016)
					(thickness 0.1524)
				)
			)
		)
		(duplicate_pad_numbers_are_jumpers no)
		(fp_line
			(start -0.508 -0.9398)
			(end -0.508 0.9398)
			(stroke
				(width 0.1524)
				(type default)
			)
			(layer "F.SilkS")
		)
		(fp_line
			(start 0.508 -0.9398)
			(end -0.508 -0.9398)
			(stroke
				(width 0.1524)
				(type default)
			)
			(layer "F.SilkS")
		)
		(fp_rect
			(start -0.508 0.9398)
			(end 0.508 -0.9398)
			(stroke
				(width 0)
				(type default)
			)
			(fill no)
			(layer "F.CrtYd")
		)
		(fp_rect
			(start -0.508 0.9398)
			(end 0.508 -0.9398)
			(stroke
				(width 0)
				(type default)
			)
			(fill no)
			(layer "F.Fab")
		)
		(pad "1" smd custom
			(at 0 -0.4445 270)
			(size 0.1397 0.1397)
			(layers "F.Cu" "F.Mask" "F.Paste")
			(net "DRIVE_A_24_PWR")
			(options
				(clearance outline)
				(anchor circle)
			)
			(primitives
				(gr_poly
					(pts
						(arc
							(start -0.1778 -0.2794)
							(mid -0.249642 -0.249642)
							(end -0.2794 -0.1778)
						)
						(arc
							(start -0.2794 0.1778)
							(mid -0.249642 0.249642)
							(end -0.1778 0.2794)
						)
						(arc
							(start 0.1778 0.2794)
							(mid 0.249642 0.249642)
							(end 0.2794 0.1778)
						)
						(arc
							(start 0.2794 -0.1778)
							(mid 0.249642 -0.249642)
							(end 0.1778 -0.2794)
						)
					)
					(width 0)
					(fill yes)
				)
			)
		)
		(pad "2" smd custom
			(at 0 0.4445 270)
			(size 0.1397 0.1397)
			(layers "F.Cu" "F.Mask" "F.Paste")
			(net "SW_PWR_R_HDD24")
			(options
				(clearance outline)
				(anchor circle)
			)
			(primitives
				(gr_poly
					(pts
						(arc
							(start -0.1778 -0.2794)
							(mid -0.249642 -0.249642)
							(end -0.2794 -0.1778)
						)
						(arc
							(start -0.2794 0.1778)
							(mid -0.249642 0.249642)
							(end -0.1778 0.2794)
						)
						(arc
							(start 0.1778 0.2794)
							(mid 0.249642 0.249642)
							(end 0.2794 0.1778)
						)
						(arc
							(start 0.2794 -0.1778)
							(mid 0.249642 -0.249642)
							(end 0.1778 -0.2794)
						)
					)
					(width 0)
					(fill yes)
				)
			)
		)
	)
	(footprint ""
		(layer "F.Cu")
		(at 219.856558 -9.457436 90)
		(property "Reference" "C46"
			(at 0 0 90)
			(layer "F.SilkS")
			(hide yes)
			(effects
				(font
					(size 1.27 1.27)
				)
			)
		)
		(property "Value" "SC1U16V3KX-5GP"
			(at 0 -2.8194 90)
			(unlocked yes)
			(layer "F.Fab")
			(hide yes)
			(effects
				(font
					(size 1.016 1.016)
					(thickness 0.1524)
				)
			)
		)
		(property "Device Type" "C603H36"
			(at 0 -4.3434 90)
			(unlocked yes)
			(layer "F.Fab")
			(hide yes)
			(effects
				(font
					(size 1.016 1.016)
					(thickness 0.1524)
				)
			)
		)
		(duplicate_pad_numbers_are_jumpers no)
		(fp_line
			(start 0.508 0)
			(end -0.508 0)
			(stroke
				(width 0.2032)
				(type default)
			)
			(layer "F.SilkS")
		)
		(fp_rect
			(start -0.5842 1.3335)
			(end 0.5842 -1.3335)
			(stroke
				(width 0)
				(type default)
			)
			(fill no)
			(layer "F.CrtYd")
		)
		(fp_rect
			(start -0.5842 1.3335)
			(end 0.5842 -1.3335)
			(stroke
				(width 0)
				(type default)
			)
			(fill no)
			(layer "F.Fab")
		)
		(pad "1" smd custom
			(at 0 -0.762 90)
			(size 0.2159 0.2159)
			(layers "F.Cu" "F.Mask" "F.Paste")
			(net "P5V_A_2")
			(options
				(clearance outline)
				(anchor circle)
			)
			(primitives
				(gr_poly
					(pts
						(arc
							(start -0.3302 -0.4318)
							(mid -0.402042 -0.402042)
							(end -0.4318 -0.3302)
						)
						(arc
							(start -0.4318 0.3302)
							(mid -0.402042 0.402042)
							(end -0.3302 0.4318)
						)
						(arc
							(start 0.3302 0.4318)
							(mid 0.402042 0.402042)
							(end 0.4318 0.3302)
						)
						(arc
							(start 0.4318 -0.3302)
							(mid 0.402042 -0.402042)
							(end 0.3302 -0.4318)
						)
					)
					(width 0)
					(fill yes)
				)
			)
		)
		(pad "2" smd custom
			(at 0 0.762 90)
			(size 0.2159 0.2159)
			(layers "F.Cu" "F.Mask" "F.Paste")
			(net "GND")
			(options
				(clearance outline)
				(anchor circle)
			)
			(primitives
				(gr_poly
					(pts
						(arc
							(start -0.3302 -0.4318)
							(mid -0.402042 -0.402042)
							(end -0.4318 -0.3302)
						)
						(arc
							(start -0.4318 0.3302)
							(mid -0.402042 0.402042)
							(end -0.3302 0.4318)
						)
						(arc
							(start 0.3302 0.4318)
							(mid 0.402042 0.402042)
							(end 0.4318 0.3302)
						)
						(arc
							(start 0.4318 -0.3302)
							(mid 0.402042 -0.402042)
							(end 0.3302 -0.4318)
						)
					)
					(width 0)
					(fill yes)
				)
			)
		)
	)
)
